FILE_TYPE = CONNECTIVITY;
{Allegro Design Entry HDL 16.6-p007 (v16-6-112F) 10/10/2012}
"PAGE_NUMBER" = 3;
0"NC";
END.
